(kicad_pcb
	(version 20260206)
	(generator "pcbnew")
	(generator_version "10.0")
	(general
		(thickness 1.21888)
		(legacy_teardrops no)
	)
	(paper "A4")
	(title_block
		(title "timecard-proto-v0 — Timingcard_PCB.PcbDoc")
		(comment 1 "Time Appliance Project (Time Card) / footprints 135-146 of 167")
	)
	(layers
		(0 "F.Cu" signal "TOP")
		(4 "In1.Cu" signal "SGND")
		(6 "In2.Cu" signal "IN1")
		(8 "In3.Cu" signal "IN2")
		(10 "In4.Cu" signal "SGND1")
		(2 "B.Cu" signal "BOTTOM")
		(9 "F.Adhes" user "F.Adhesive")
		(11 "B.Adhes" user "B.Adhesive")
		(13 "F.Paste" user "Top Paste")
		(15 "B.Paste" user "Bottom Paste")
		(5 "F.SilkS" user "Top Overlay")
		(7 "B.SilkS" user "Bottom Overlay")
		(1 "F.Mask" user "Top Solder")
		(3 "B.Mask" user "Bottom Solder")
		(17 "Dwgs.User" user "User.Drawings")
		(19 "Cmts.User" user "User.Comments")
		(21 "Eco1.User" user "User.Eco1")
		(23 "Eco2.User" user "User.Eco2")
		(25 "Edge.Cuts" user)
		(27 "Margin" user)
		(31 "F.CrtYd" user "Top Courtyard")
		(29 "B.CrtYd" user "Bottom Courtyard")
		(35 "F.Fab" user "Top Component Center")
		(33 "B.Fab" user "Bottom Component Center")
	)
	(footprint "IntegratedCircuits:SOIC127P600X175-8N"
		(layer "F.Cu")
		(at 229.553595 110.8946)
		(property "Reference" "U1"
			(at -4.415 -2.972655 0)
			(unlocked yes)
			(layer "F.SilkS")
			(effects
				(font
					(size 0.762 0.762)
					(thickness 0.2286)
				)
				(justify left bottom)
			)
		)
		(property "Value" "MP1482DS-LF"
			(at -6.9469 5.15239 0)
			(unlocked yes)
			(layer "F.SilkS")
			(hide yes)
			(effects
				(font
					(size 1.524 1.524)
					(thickness 0.254)
				)
				(justify left bottom)
			)
		)
		(sheetname "POWER")
		(sheetfile "POWER.kicad_sch")
		(duplicate_pad_numbers_are_jumpers no)
		(fp_line
			(start -3.4 -2.5)
			(end 2 -2.5)
			(stroke
				(width 0.12)
				(type solid)
			)
			(layer "F.SilkS")
		)
		(fp_line
			(start -2 2.5)
			(end 2 2.5)
			(stroke
				(width 0.12)
				(type solid)
			)
			(layer "F.SilkS")
		)
		(pad "1" smd rect
			(at -2.475 -1.905)
			(size 1.97 0.57)
			(layers "F.Cu" "F.Mask" "F.Paste")
			(net "NetC4_1")
		)
		(pad "2" smd rect
			(at -2.475 -0.635)
			(size 1.97 0.57)
			(layers "F.Cu" "F.Mask" "F.Paste")
			(net "+12V")
		)
		(pad "3" smd rect
			(at -2.475 0.635)
			(size 1.97 0.57)
			(layers "F.Cu" "F.Mask" "F.Paste")
			(net "NetC4_2")
		)
		(pad "4" smd rect
			(at -2.475 1.905)
			(size 1.97 0.57)
			(layers "F.Cu" "F.Mask" "F.Paste")
			(net "GND")
		)
		(pad "5" smd rect
			(at 2.475 1.905)
			(size 1.97 0.57)
			(layers "F.Cu" "F.Mask" "F.Paste")
			(net "NetR4_2")
		)
		(pad "6" smd rect
			(at 2.475 0.635)
			(size 1.97 0.57)
			(layers "F.Cu" "F.Mask" "F.Paste")
			(net "NetC20_2")
		)
		(pad "7" smd rect
			(at 2.475 -0.635)
			(size 1.97 0.57)
			(layers "F.Cu" "F.Mask" "F.Paste")
			(net "NetR2_1")
		)
		(pad "8" smd rect
			(at 2.475 -1.905)
			(size 1.97 0.57)
			(layers "F.Cu" "F.Mask" "F.Paste")
			(net "NetC19_2")
		)
	)
	(footprint "Resistors:RESC1608X50N"
		(layer "F.Cu")
		(at 230.288595 114.3786)
		(property "Reference" "R6"
			(at -3.398 0.321345 0)
			(unlocked yes)
			(layer "F.SilkS")
			(effects
				(font
					(size 0.762 0.762)
					(thickness 0.2286)
				)
				(justify left bottom)
			)
		)
		(property "Value" "ERJ-3EKF1002V"
			(at -4.4323 3.04419 0)
			(unlocked yes)
			(layer "F.SilkS")
			(hide yes)
			(effects
				(font
					(size 1.524 1.524)
					(thickness 0.254)
				)
				(justify left bottom)
			)
		)
		(sheetname "POWER")
		(sheetfile "POWER.kicad_sch")
		(duplicate_pad_numbers_are_jumpers no)
		(fp_line
			(start 0 0.5)
			(end 0 -0.5)
			(stroke
				(width 0.1524)
				(type solid)
			)
			(layer "F.SilkS")
		)
		(pad "1" smd rect
			(at -0.69 0 90)
			(size 1 0.72)
			(layers "F.Cu" "F.Mask" "F.Paste")
			(net "GND")
		)
		(pad "2" smd rect
			(at 0.69 0 90)
			(size 1 0.72)
			(layers "F.Cu" "F.Mask" "F.Paste")
			(net "NetR4_2")
		)
	)
	(footprint "Resistors:RESC1608X50N"
		(layer "F.Cu")
		(at 219.488595 98.0786 180)
		(property "Reference" "R7"
			(at 3.982 -0.350345 0)
			(unlocked yes)
			(layer "F.SilkS")
			(effects
				(font
					(size 0.762 0.762)
					(thickness 0.2286)
				)
				(justify left bottom)
			)
		)
		(property "Value" "ERJ-3EKF1002V"
			(at -10.9347 3.94081 0)
			(unlocked yes)
			(layer "F.SilkS")
			(hide yes)
			(effects
				(font
					(size 1.524 1.524)
					(thickness 0.254)
				)
				(justify left bottom)
			)
		)
		(sheetname "POWER")
		(sheetfile "POWER.kicad_sch")
		(duplicate_pad_numbers_are_jumpers no)
		(fp_line
			(start 0 -0.5)
			(end 0 0.5)
			(stroke
				(width 0.1524)
				(type solid)
			)
			(layer "F.SilkS")
		)
		(pad "1" smd rect
			(at -0.69 0 270)
			(size 1 0.72)
			(layers "F.Cu" "F.Mask" "F.Paste")
			(net "GND")
		)
		(pad "2" smd rect
			(at 0.69 0 270)
			(size 1 0.72)
			(layers "F.Cu" "F.Mask" "F.Paste")
			(net "NetR5_1")
		)
	)
	(footprint "Resistors:RESC1608X50N"
		(layer "F.Cu")
		(at 164.603595 69.0536)
		(property "Reference" "R1"
			(at -3.215 0.418345 0)
			(unlocked yes)
			(layer "F.SilkS")
			(effects
				(font
					(size 0.762 0.762)
					(thickness 0.2286)
				)
				(justify left bottom)
			)
		)
		(property "Value" "ERJ-3EKF2000V"
			(at -1.0033 3.17119 0)
			(unlocked yes)
			(layer "F.SilkS")
			(hide yes)
			(effects
				(font
					(size 1.524 1.524)
					(thickness 0.254)
				)
				(justify left bottom)
			)
		)
		(sheetname "POWER")
		(sheetfile "POWER.kicad_sch")
		(duplicate_pad_numbers_are_jumpers no)
		(fp_line
			(start 0 0.5)
			(end 0 -0.5)
			(stroke
				(width 0.1524)
				(type solid)
			)
			(layer "F.SilkS")
		)
		(pad "1" smd rect
			(at -0.69 0 90)
			(size 1 0.72)
			(layers "F.Cu" "F.Mask" "F.Paste")
			(net "GND")
		)
		(pad "2" smd rect
			(at 0.69 0 90)
			(size 1 0.72)
			(layers "F.Cu" "F.Mask" "F.Paste")
			(net "NetD4_1")
		)
	)
	(footprint "Miscellaneous Devices:J1-0603"
		(layer "F.Cu")
		(at 82.388595 102.7786 180)
		(property "Reference" "R15"
			(at -3.054 0.073079 0)
			(unlocked yes)
			(layer "F.SilkS")
			(effects
				(font
					(size 0.762 0.762)
					(thickness 0.254)
				)
			)
		)
		(property "Value" "MACPPSI"
			(at -4.98946 -2.835402 0)
			(unlocked yes)
			(layer "F.SilkS")
			(hide yes)
			(effects
				(font
					(size 1.524 1.524)
					(thickness 0.254)
				)
			)
		)
		(sheetname "USER_IO")
		(sheetfile "USER_IO.kicad_sch")
		(duplicate_pad_numbers_are_jumpers no)
		(fp_line
			(start 0.2 0.35)
			(end -0.2 0.35)
			(stroke
				(width 0.2)
				(type solid)
			)
			(layer "F.SilkS")
		)
		(fp_line
			(start 0.2 -0.35)
			(end -0.2 -0.35)
			(stroke
				(width 0.2)
				(type solid)
			)
			(layer "F.SilkS")
		)
		(pad "1" smd rect
			(at -0.75 0 270)
			(size 0.9 0.7)
			(layers "F.Cu" "F.Mask" "F.Paste")
			(net "MAC_PPS_IN0+")
		)
		(pad "2" smd rect
			(at 0.75 0 270)
			(size 0.9 0.7)
			(layers "F.Cu" "F.Mask" "F.Paste")
			(net "ANT1")
		)
	)
	(footprint "Resistors:RESC2012X50N"
		(layer "F.Cu")
		(at 138.367595 66.4446 90)
		(property "Reference" "R20"
			(at -4.97791 0.690065 90)
			(unlocked yes)
			(layer "F.SilkS")
			(effects
				(font
					(size 0.762 0.762)
					(thickness 0.2286)
				)
				(justify left bottom)
			)
		)
		(property "Value" "CRCW080533R0FKEA"
			(at -3.52679 -1.5875 0)
			(unlocked yes)
			(layer "F.SilkS")
			(hide yes)
			(effects
				(font
					(size 1.524 1.524)
					(thickness 0.254)
				)
				(justify left bottom)
			)
		)
		(sheetname "PCIe_JTAG")
		(sheetfile "PCIe_JTAG.kicad_sch")
		(duplicate_pad_numbers_are_jumpers no)
		(fp_line
			(start 0 -0.762)
			(end 0 0.762)
			(stroke
				(width 0.1524)
				(type solid)
			)
			(layer "F.SilkS")
		)
		(pad "1" smd rect
			(at -1 0 180)
			(size 1.45 0.95)
			(layers "F.Cu" "F.Mask" "F.Paste")
			(net "FPGA_TMS")
		)
		(pad "2" smd rect
			(at 1 0 180)
			(size 1.45 0.95)
			(layers "F.Cu" "F.Mask" "F.Paste")
			(net "NetR20_2")
		)
	)
	(footprint "Vault:RESC1608X55X30NL15T15"
		(layer "F.Cu")
		(at 90.188595 56.9786 90)
		(property "Reference" "R30"
			(at -1.3 -1.206655 90)
			(unlocked yes)
			(layer "F.SilkS")
			(effects
				(font
					(size 0.762 0.762)
					(thickness 0.2286)
				)
				(justify left bottom)
			)
		)
		(property "Value" "200 OHM"
			(at -3.72999 -0.4445 0)
			(unlocked yes)
			(layer "F.SilkS")
			(hide yes)
			(effects
				(font
					(size 1.524 1.524)
					(thickness 0.254)
				)
				(justify left bottom)
			)
		)
		(sheetname "USER_IO")
		(sheetfile "USER_IO.kicad_sch")
		(duplicate_pad_numbers_are_jumpers no)
		(pad "1" smd rect
			(at -0.675 0 180)
			(size 0.95 0.8)
			(layers "F.Cu" "F.Mask" "F.Paste")
			(net "LED4")
		)
		(pad "2" smd rect
			(at 0.675 0 180)
			(size 0.95 0.8)
			(layers "F.Cu" "F.Mask" "F.Paste")
			(net "NetD14_1")
		)
	)
	(footprint "Resistors:RESC2012X50N"
		(layer "F.Cu")
		(at 133.287595 66.4446 90)
		(property "Reference" "R18"
			(at -4.88269 0.791665 90)
			(unlocked yes)
			(layer "F.SilkS")
			(effects
				(font
					(size 0.762 0.762)
					(thickness 0.2286)
				)
				(justify left bottom)
			)
		)
		(property "Value" "CRCW080533R0FKEA"
			(at -3.52679 -1.5875 0)
			(unlocked yes)
			(layer "F.SilkS")
			(hide yes)
			(effects
				(font
					(size 1.524 1.524)
					(thickness 0.254)
				)
				(justify left bottom)
			)
		)
		(sheetname "PCIe_JTAG")
		(sheetfile "PCIe_JTAG.kicad_sch")
		(duplicate_pad_numbers_are_jumpers no)
		(fp_line
			(start 0 -0.762)
			(end 0 0.762)
			(stroke
				(width 0.1524)
				(type solid)
			)
			(layer "F.SilkS")
		)
		(pad "1" smd rect
			(at -1 0 180)
			(size 1.45 0.95)
			(layers "F.Cu" "F.Mask" "F.Paste")
			(net "FPGA_TCK")
		)
		(pad "2" smd rect
			(at 1 0 180)
			(size 1.45 0.95)
			(layers "F.Cu" "F.Mask" "F.Paste")
			(net "NetR18_2")
		)
	)
	(footprint "Vault:CAPC1608X87X45ML20T05"
		(layer "F.Cu")
		(at 173.388595 63.5786 90)
		(property "Reference" "C25"
			(at 3.3286 0.026931 90)
			(unlocked yes)
			(layer "F.SilkS")
			(effects
				(font
					(size 0.762 0.762)
					(thickness 0.2286)
				)
			)
		)
		(property "Value" "0.1uF"
			(at 2.09443 2.657602 90)
			(unlocked yes)
			(layer "F.SilkS")
			(hide yes)
			(effects
				(font
					(size 1.524 1.524)
					(thickness 0.254)
				)
			)
		)
		(sheetname "GPS_IMU_SENSORS")
		(sheetfile "GPS_IMU_SENSORS.kicad_sch")
		(duplicate_pad_numbers_are_jumpers no)
		(pad "1" smd rect
			(at -0.7 0 180)
			(size 1.1 1.05)
			(layers "F.Cu" "F.Mask" "F.Paste")
			(net "GND")
		)
		(pad "2" smd rect
			(at 0.7 0 180)
			(size 1.1 1.05)
			(layers "F.Cu" "F.Mask" "F.Paste")
			(net "+3.3V")
		)
	)
	(footprint "Connectors:AMPHENOL-901-143-6RFX"
		(layer "F.Cu")
		(at 63.564595 124.2296 180)
		(property "Reference" "AN3"
			(at -5.25829 -4.627055 0)
			(unlocked yes)
			(layer "F.SilkS")
			(effects
				(font
					(size 0.762 0.762)
					(thickness 0.2286)
				)
				(justify left bottom)
			)
		)
		(property "Value" "RF-901-143-6FRX"
			(at 4.6101 -2.05359 0)
			(unlocked yes)
			(layer "F.SilkS")
			(hide yes)
			(effects
				(font
					(size 1.524 1.524)
					(thickness 0.254)
				)
				(justify left bottom)
			)
		)
		(sheetfile ".kicad_sch")
		(duplicate_pad_numbers_are_jumpers no)
		(fp_line
			(start 4.318 3.556)
			(end 3.302 4.572)
			(stroke
				(width 0.1778)
				(type solid)
			)
			(layer "F.SilkS")
		)
		(fp_line
			(start 4.318 -3.556)
			(end 3.302 -4.572)
			(stroke
				(width 0.1778)
				(type solid)
			)
			(layer "F.SilkS")
		)
		(fp_line
			(start 3.302 4.572)
			(end 2.54 4.572)
			(stroke
				(width 0.1778)
				(type solid)
			)
			(layer "F.SilkS")
		)
		(fp_line
			(start 3.302 -4.572)
			(end 2.54 -4.572)
			(stroke
				(width 0.1778)
				(type solid)
			)
			(layer "F.SilkS")
		)
		(fp_line
			(start 2.54 4.572)
			(end -4.572 4.572)
			(stroke
				(width 0.1778)
				(type solid)
			)
			(layer "F.SilkS")
		)
		(fp_line
			(start 2.54 -4.572)
			(end -4.572 -4.572)
			(stroke
				(width 0.1778)
				(type solid)
			)
			(layer "F.SilkS")
		)
		(fp_line
			(start -4.572 2.54)
			(end -4.572 4.572)
			(stroke
				(width 0.1778)
				(type solid)
			)
			(layer "F.SilkS")
		)
		(fp_line
			(start -4.572 -4.572)
			(end -4.572 -2.54)
			(stroke
				(width 0.1778)
				(type solid)
			)
			(layer "F.SilkS")
		)
		(pad "1" thru_hole circle
			(at 0 0 180)
			(size 2.8448 2.8448)
			(drill 1.524)
			(layers "*.Cu" "*.Mask")
			(remove_unused_layers no)
			(net "ANT3")
			(thermal_bridge_angle 90)
		)
		(pad "2" thru_hole circle
			(at -2.54 2.54 180)
			(size 3.048 3.048)
			(drill 1.7272)
			(layers "*.Cu" "*.Mask")
			(remove_unused_layers no)
			(net "GND")
			(thermal_bridge_angle 90)
		)
		(pad "3" thru_hole circle
			(at -2.54 -2.54 180)
			(size 3.048 3.048)
			(drill 1.7272)
			(layers "*.Cu" "*.Mask")
			(remove_unused_layers no)
			(net "GND")
			(thermal_bridge_angle 90)
		)
		(pad "4" thru_hole circle
			(at 2.54 -2.54 180)
			(size 3.048 3.048)
			(drill 1.7272)
			(layers "*.Cu" "*.Mask")
			(remove_unused_layers no)
			(net "GND")
			(thermal_bridge_angle 90)
		)
		(pad "5" thru_hole circle
			(at 2.54 2.54 180)
			(size 3.048 3.048)
			(drill 1.7272)
			(layers "*.Cu" "*.Mask")
			(remove_unused_layers no)
			(net "GND")
			(thermal_bridge_angle 90)
		)
	)
	(footprint "Vault:FP-BU2032SM-BT-GTR-MFG"
		(layer "F.Cu")
		(at 183.188595 74.6036 90)
		(property "Reference" "BT1"
			(at 15.498069 -6.645995 0)
			(unlocked yes)
			(layer "F.SilkS")
			(effects
				(font
					(size 0.762 0.762)
					(thickness 0.254)
				)
			)
		)
		(property "Value" "BU2032SM-BT-GTR"
			(at -19.269202 3.234885 0)
			(unlocked yes)
			(layer "F.SilkS")
			(hide yes)
			(effects
				(font
					(size 1.524 1.524)
					(thickness 0.254)
				)
			)
		)
		(sheetname "MAC")
		(sheetfile "MAC.kicad_sch")
		(duplicate_pad_numbers_are_jumpers no)
		(fp_line
			(start 14.55 -8.25)
			(end 14.55 -2.475)
			(stroke
				(width 0.2)
				(type solid)
			)
			(layer "F.SilkS")
		)
		(fp_line
			(start -14.55 -8.25)
			(end 14.55 -8.25)
			(stroke
				(width 0.2)
				(type solid)
			)
			(layer "F.SilkS")
		)
		(fp_line
			(start -14.55 -8.25)
			(end -14.55 -2.475)
			(stroke
				(width 0.2)
				(type solid)
			)
			(layer "F.SilkS")
		)
		(fp_line
			(start -17.3 -0.3)
			(end -17.3 0.3)
			(stroke
				(width 0.2)
				(type solid)
			)
			(layer "F.SilkS")
		)
		(fp_line
			(start -17.6 0)
			(end -17 0)
			(stroke
				(width 0.2)
				(type solid)
			)
			(layer "F.SilkS")
		)
		(fp_line
			(start 14.55 2.475)
			(end 14.55 8.25)
			(stroke
				(width 0.2)
				(type solid)
			)
			(layer "F.SilkS")
		)
		(fp_line
			(start -14.55 2.475)
			(end -14.55 8.25)
			(stroke
				(width 0.2)
				(type solid)
			)
			(layer "F.SilkS")
		)
		(fp_line
			(start -14.55 8.25)
			(end 14.55 8.25)
			(stroke
				(width 0.2)
				(type solid)
			)
			(layer "F.SilkS")
		)
		(fp_line
			(start 16.35 -8.35)
			(end 16.35 8.35)
			(stroke
				(width 0.2)
				(type solid)
			)
			(layer "F.CrtYd")
		)
		(fp_line
			(start -16.35 -8.35)
			(end 16.35 -8.35)
			(stroke
				(width 0.2)
				(type solid)
			)
			(layer "F.CrtYd")
		)
		(fp_line
			(start -16.35 -8.35)
			(end -16.35 8.35)
			(stroke
				(width 0.2)
				(type solid)
			)
			(layer "F.CrtYd")
		)
		(fp_line
			(start -16.35 8.35)
			(end 16.35 8.35)
			(stroke
				(width 0.2)
				(type solid)
			)
			(layer "F.CrtYd")
		)
		(fp_line
			(start 16.35 -8.35)
			(end 16.35 8.35)
			(stroke
				(width 0.2)
				(type solid)
			)
			(layer "F.Fab")
		)
		(fp_line
			(start -16.35 -8.35)
			(end 16.35 -8.35)
			(stroke
				(width 0.2)
				(type solid)
			)
			(layer "F.Fab")
		)
		(fp_line
			(start -16.35 -8.35)
			(end -16.35 8.35)
			(stroke
				(width 0.2)
				(type solid)
			)
			(layer "F.Fab")
		)
		(fp_line
			(start 0 -0.5)
			(end 0 0.5)
			(stroke
				(width 0.1)
				(type solid)
			)
			(layer "F.Fab")
		)
		(fp_line
			(start -0.5 0)
			(end 0.5 0)
			(stroke
				(width 0.1)
				(type solid)
			)
			(layer "F.Fab")
		)
		(fp_line
			(start -16.35 8.35)
			(end 16.35 8.35)
			(stroke
				(width 0.2)
				(type solid)
			)
			(layer "F.Fab")
		)
		(fp_text user "${REFERENCE}"
			(at 0 0.29535 90)
			(unlocked yes)
			(layer "F.Fab")
			(effects
				(font
					(face "Arial")
					(size 0.63 0.63)
					(thickness 0.1)
				)
				(justify left bottom)
			)
		)
		(pad "1" smd rect
			(at 14.65 0 90)
			(size 3.2 4.2)
			(layers "F.Cu" "F.Mask" "F.Paste")
			(net "GND")
			(solder_mask_margin 0)
			(solder_paste_margin 0)
		)
		(pad "2" smd rect
			(at -14.65 0 90)
			(size 3.2 4.2)
			(layers "F.Cu" "F.Mask" "F.Paste")
			(net "NetBT1_2")
			(solder_mask_margin 0)
			(solder_paste_margin 0)
		)
	)
	(footprint "Capacitors:CAPC1608X10N"
		(layer "F.Cu")
		(at 226.251595 80.2876 90)
		(property "Reference" "C85"
			(at 5.409 1.730345 90)
			(unlocked yes)
			(layer "F.SilkS")
			(effects
				(font
					(size 0.762 0.762)
					(thickness 0.2286)
				)
				(justify left bottom)
			)
		)
		(property "Value" "CAP_0603_22PF_50V"
			(at -1.03759 10.3759 0)
			(unlocked yes)
			(layer "F.SilkS")
			(hide yes)
			(effects
				(font
					(size 1.524 1.524)
					(thickness 0.254)
				)
				(justify left bottom)
			)
		)
		(sheetname "GPS_IMU_SENSORS")
		(sheetfile "GPS_IMU_SENSORS.kicad_sch")
		(duplicate_pad_numbers_are_jumpers no)
		(fp_line
			(start -0.635 -0.7112)
			(end 0.635 -0.7112)
			(stroke
				(width 0.1524)
				(type solid)
			)
			(layer "F.SilkS")
		)
		(fp_line
			(start -0.635 0.7112)
			(end 0.635 0.7112)
			(stroke
				(width 0.1524)
				(type solid)
			)
			(layer "F.SilkS")
		)
		(pad "1" smd rect
			(at -0.8 0 180)
			(size 0.95 1)
			(layers "F.Cu" "F.Mask" "F.Paste")
			(net "GND")
		)
		(pad "2" smd rect
			(at 0.8 0 180)
			(size 0.95 1)
			(layers "F.Cu" "F.Mask" "F.Paste")
			(net "NetC85_2")
		)
	)
)
